# S9S_MB_2U (Grand Teton) — schematic netlist excerpt (pin names and nets, part order shuffled) for the footprints in the layout excerpt that follows; sources: Cadence DE-HDL packaged netlist, KiCad conversion of 03242023_DA0F0TMBIJ0_F0T_Motherboard_J_brd_V01_OCP.brd

PC569  Q_CAP  220PF 50V 10% X7R  pkg 0402  page 259 : A = P3V3_AUX_FB ; B = P3V3_AUX
R3327  Q_RES  0 5% CHIP  pkg 0402LF  page 212 : A = CLK_GEN2_GPU_FPGA_OE_N ; B = CLK_GEN2_GPU_FPGA_OE_R2_N

(kicad_pcb
	(version 20260206)
	(generator "pcbnew")
	(generator_version "10.0")
	(general
		(thickness 1.6)
		(legacy_teardrops no)
	)
	(paper "A4")
	(title_block
		(title "03242023_DA0F0TMBIJ0_F0T_Motherboard_J_brd_V01_OCP.brd")
		(comment 1 "Grand Teton / footprints 3429-3430 of 6105")
	)
	(layers
		(0 "F.Cu" signal "TOP")
		(4 "In1.Cu" signal "GND")
		(6 "In2.Cu" signal "IN1")
		(8 "In3.Cu" signal "GND1")
		(10 "In4.Cu" signal "IN2")
		(12 "In5.Cu" signal "GND2")
		(14 "In6.Cu" signal "IN3")
		(16 "In7.Cu" signal "GND3")
		(18 "In8.Cu" signal "VCC")
		(20 "In9.Cu" signal "VCC1")
		(22 "In10.Cu" signal "GND4")
		(24 "In11.Cu" signal "IN4")
		(26 "In12.Cu" signal "GND5")
		(28 "In13.Cu" signal "IN5")
		(30 "In14.Cu" signal "GND6")
		(32 "In15.Cu" signal "IN6")
		(34 "In16.Cu" signal "GND7")
		(2 "B.Cu" signal "BOTTOM")
		(9 "F.Adhes" user "F.Adhesive")
		(11 "B.Adhes" user "B.Adhesive")
		(13 "F.Paste" user "Package Geometry/Pastemask Top")
		(15 "B.Paste" user "Package Geometry/Pastemask Bottom")
		(5 "F.SilkS" user "Ref Des/Silkscreen Top")
		(7 "B.SilkS" user "Ref Des/Silkscreen Bottom")
		(1 "F.Mask" user "Board Geometry/Soldermask Top")
		(3 "B.Mask" user "Board Geometry/Soldermask Bottom")
		(17 "Dwgs.User" user "User.Drawings")
		(19 "Cmts.User" user "User.Comments")
		(21 "Eco1.User" user "User.Eco1")
		(23 "Eco2.User" user "User.Eco2")
		(25 "Edge.Cuts" user "Board Geometry/Outline")
		(27 "Margin" user)
		(31 "F.CrtYd" user "Package Geometry/Place Bound Top")
		(29 "B.CrtYd" user "Package Geometry/Place Bound Bottom")
		(35 "F.Fab" user "Ref Des/Assembly Top")
		(33 "B.Fab" user "Ref Des/Assembly Bottom")
	)
	(footprint ""
		(layer "F.Cu")
		(at 449.38442 -77.829918 90)
		(property "Reference" "PC569"
			(at 0 0 90)
			(layer "F.SilkS")
			(hide yes)
			(effects
				(font
					(size 1.27 1.27)
				)
			)
		)
		(property "Value" ""
			(at 0 0 90)
			(layer "F.Fab")
			(effects
				(font
					(size 1.27 1.27)
				)
			)
		)
		(duplicate_pad_numbers_are_jumpers no)
		(fp_line
			(start 0.7874 -0.4064)
			(end 0.7874 0.4064)
			(stroke
				(width 0.1524)
				(type default)
			)
			(layer "F.SilkS")
		)
		(fp_line
			(start -0.7874 -0.4064)
			(end 0.7874 -0.4064)
			(stroke
				(width 0.1524)
				(type default)
			)
			(layer "F.SilkS")
		)
		(fp_line
			(start 0.7874 0.4064)
			(end -0.7874 0.4064)
			(stroke
				(width 0.1524)
				(type default)
			)
			(layer "F.SilkS")
		)
		(fp_line
			(start -0.7874 0.4064)
			(end -0.7874 -0.4064)
			(stroke
				(width 0.1524)
				(type default)
			)
			(layer "F.SilkS")
		)
		(fp_line
			(start -0.12065 -0.305054)
			(end -0.12065 -0.2794)
			(stroke
				(width 0.1)
				(type default)
			)
			(layer "F.Fab")
		)
		(fp_line
			(start -0.67945 -0.305054)
			(end -0.12065 -0.305054)
			(stroke
				(width 0.1)
				(type default)
			)
			(layer "F.Fab")
		)
		(fp_line
			(start 0.67945 -0.3048)
			(end 0.67945 0.3048)
			(stroke
				(width 0.1)
				(type default)
			)
			(layer "F.Fab")
		)
		(fp_line
			(start 0.12065 -0.3048)
			(end 0.67945 -0.3048)
			(stroke
				(width 0.1)
				(type default)
			)
			(layer "F.Fab")
		)
		(fp_line
			(start 0.12065 -0.2794)
			(end 0.12065 -0.3048)
			(stroke
				(width 0.1)
				(type default)
			)
			(layer "F.Fab")
		)
		(fp_line
			(start -0.12065 -0.2794)
			(end 0.12065 -0.2794)
			(stroke
				(width 0.1)
				(type default)
			)
			(layer "F.Fab")
		)
		(fp_line
			(start 0.120396 0.2794)
			(end -0.12065 0.2794)
			(stroke
				(width 0.1)
				(type default)
			)
			(layer "F.Fab")
		)
		(fp_line
			(start -0.12065 0.2794)
			(end -0.12065 0.3048)
			(stroke
				(width 0.1)
				(type default)
			)
			(layer "F.Fab")
		)
		(fp_line
			(start 0.67945 0.3048)
			(end 0.120396 0.3048)
			(stroke
				(width 0.1)
				(type default)
			)
			(layer "F.Fab")
		)
		(fp_line
			(start 0.120396 0.3048)
			(end 0.120396 0.2794)
			(stroke
				(width 0.1)
				(type default)
			)
			(layer "F.Fab")
		)
		(fp_line
			(start -0.12065 0.3048)
			(end -0.67945 0.3048)
			(stroke
				(width 0.1)
				(type default)
			)
			(layer "F.Fab")
		)
		(fp_line
			(start -0.67945 0.3048)
			(end -0.67945 -0.305054)
			(stroke
				(width 0.1)
				(type default)
			)
			(layer "F.Fab")
		)
		(pad "1" smd circle
			(at -0.40005 0 90)
			(size 0 0)
			(layers "F.Cu" "F.Mask" "F.Paste")
			(net "P3V3_AUX_FB")
		)
		(pad "2" smd circle
			(at 0.40005 0 90)
			(size 0 0)
			(layers "F.Cu" "F.Mask" "F.Paste")
			(net "P3V3_AUX")
		)
	)
	(footprint ""
		(layer "F.Cu")
		(at 113.873534 -38.065456)
		(property "Reference" "R3327"
			(at 0 0 0)
			(layer "F.SilkS")
			(hide yes)
			(effects
				(font
					(size 1.27 1.27)
				)
			)
		)
		(property "Value" ""
			(at 0 0 0)
			(layer "F.Fab")
			(effects
				(font
					(size 1.27 1.27)
				)
			)
		)
		(duplicate_pad_numbers_are_jumpers no)
		(fp_line
			(start -0.7874 -0.4064)
			(end 0.7874 -0.4064)
			(stroke
				(width 0.1524)
				(type default)
			)
			(layer "F.SilkS")
		)
		(fp_line
			(start -0.7874 0.4064)
			(end -0.7874 -0.4064)
			(stroke
				(width 0.1524)
				(type default)
			)
			(layer "F.SilkS")
		)
		(fp_line
			(start 0.7874 -0.4064)
			(end 0.7874 0.4064)
			(stroke
				(width 0.1524)
				(type default)
			)
			(layer "F.SilkS")
		)
		(fp_line
			(start 0.7874 0.4064)
			(end -0.7874 0.4064)
			(stroke
				(width 0.1524)
				(type default)
			)
			(layer "F.SilkS")
		)
		(fp_line
			(start -0.67945 -0.305054)
			(end -0.12065 -0.305054)
			(stroke
				(width 0.1)
				(type default)
			)
			(layer "F.Fab")
		)
		(fp_line
			(start -0.67945 0.3048)
			(end -0.67945 -0.305054)
			(stroke
				(width 0.1)
				(type default)
			)
			(layer "F.Fab")
		)
		(fp_line
			(start -0.12065 -0.305054)
			(end -0.12065 -0.2794)
			(stroke
				(width 0.1)
				(type default)
			)
			(layer "F.Fab")
		)
		(fp_line
			(start -0.12065 -0.2794)
			(end 0.12065 -0.2794)
			(stroke
				(width 0.1)
				(type default)
			)
			(layer "F.Fab")
		)
		(fp_line
			(start -0.12065 0.2794)
			(end -0.12065 0.3048)
			(stroke
				(width 0.1)
				(type default)
			)
			(layer "F.Fab")
		)
		(fp_line
			(start -0.12065 0.3048)
			(end -0.67945 0.3048)
			(stroke
				(width 0.1)
				(type default)
			)
			(layer "F.Fab")
		)
		(fp_line
			(start 0.120396 0.2794)
			(end -0.12065 0.2794)
			(stroke
				(width 0.1)
				(type default)
			)
			(layer "F.Fab")
		)
		(fp_line
			(start 0.120396 0.3048)
			(end 0.120396 0.2794)
			(stroke
				(width 0.1)
				(type default)
			)
			(layer "F.Fab")
		)
		(fp_line
			(start 0.12065 -0.3048)
			(end 0.67945 -0.3048)
			(stroke
				(width 0.1)
				(type default)
			)
			(layer "F.Fab")
		)
		(fp_line
			(start 0.12065 -0.2794)
			(end 0.12065 -0.3048)
			(stroke
				(width 0.1)
				(type default)
			)
			(layer "F.Fab")
		)
		(fp_line
			(start 0.67945 -0.3048)
			(end 0.67945 0.3048)
			(stroke
				(width 0.1)
				(type default)
			)
			(layer "F.Fab")
		)
		(fp_line
			(start 0.67945 0.3048)
			(end 0.120396 0.3048)
			(stroke
				(width 0.1)
				(type default)
			)
			(layer "F.Fab")
		)
		(pad "1" smd circle
			(at -0.40005 0)
			(size 0 0)
			(layers "F.Cu" "F.Mask" "F.Paste")
			(net "CLK_GEN2_GPU_FPGA_OE_N")
		)
		(pad "2" smd circle
			(at 0.40005 0)
			(size 0 0)
			(layers "F.Cu" "F.Mask" "F.Paste")
			(net "CLK_GEN2_GPU_FPGA_OE_R2_N")
		)
	)
)
